# SCM (Grand Teton) — schematic netlist excerpt (pin names and nets, part order shuffled) for the footprints in the layout excerpt that follows; sources: Cadence DE-HDL packaged netlist, KiCad conversion of 12092022_DA0F0TMDCD0_F0T_Management_Board_D_brd_V3_OCP.brd

R101  Q_RES  4.7K 1% CHIP  pkg 0402LF  page 11 : A = P3V3_AUX ; B = RMII_RXER
DM2  DUMMY_SYMBOL  BMC_FLASH EMPTY  pkg TP30_FOR_BOM  page 59 : \1\ = NC

U51  NC7SB3157  NC7SB3157P6X IC  pkg SMLF  page 31
  B1  = UART_BIC_DBG_RX_R
  GND  = GND
  B0  = UART_6_BMC_TXD_R
  A  = UART_BIC_GF_TXD
  VCC  = P3V3_AUX
  S  = FM_BIC_DEBUG_SW_N

(kicad_pcb
	(version 20260206)
	(generator "pcbnew")
	(generator_version "10.0")
	(general
		(thickness 1.6)
		(legacy_teardrops no)
	)
	(paper "A4")
	(title_block
		(title "12092022_DA0F0TMDCD0_F0T_Management_Board_D_brd_V3_OCP.brd")
		(comment 1 "Grand Teton / footprints 579-581 of 1440")
	)
	(layers
		(0 "F.Cu" signal "TOP")
		(4 "In1.Cu" signal "GND")
		(6 "In2.Cu" signal "IN1")
		(8 "In3.Cu" signal "GND1")
		(10 "In4.Cu" signal "IN2")
		(12 "In5.Cu" signal "VCC")
		(14 "In6.Cu" signal "VCC1")
		(16 "In7.Cu" signal "IN3")
		(18 "In8.Cu" signal "GND2")
		(20 "In9.Cu" signal "IN4")
		(22 "In10.Cu" signal "GND3")
		(2 "B.Cu" signal "BOTTOM")
		(9 "F.Adhes" user "F.Adhesive")
		(11 "B.Adhes" user "B.Adhesive")
		(13 "F.Paste" user "Package Geometry/Pastemask Top")
		(15 "B.Paste" user "Package Geometry/Pastemask Bottom")
		(5 "F.SilkS" user "Ref Des/Silkscreen Top")
		(7 "B.SilkS" user "Ref Des/Silkscreen Bottom")
		(1 "F.Mask" user "Board Geometry/Soldermask Top")
		(3 "B.Mask" user "Board Geometry/Soldermask Bottom")
		(17 "Dwgs.User" user "User.Drawings")
		(19 "Cmts.User" user "User.Comments")
		(21 "Eco1.User" user "User.Eco1")
		(23 "Eco2.User" user "User.Eco2")
		(25 "Edge.Cuts" user "Board Geometry/Outline")
		(27 "Margin" user)
		(31 "F.CrtYd" user "Package Geometry/Place Bound Top")
		(29 "B.CrtYd" user "Package Geometry/Place Bound Bottom")
		(35 "F.Fab" user "Ref Des/Assembly Top")
		(33 "B.Fab" user "Ref Des/Assembly Bottom")
	)
	(footprint ""
		(layer "F.Cu")
		(at 48.852836 -109.411008 90)
		(property "Reference" "R101"
			(at 0 0 90)
			(layer "F.SilkS")
			(hide yes)
			(effects
				(font
					(size 1.27 1.27)
				)
			)
		)
		(property "Value" ""
			(at 0 0 90)
			(layer "F.Fab")
			(effects
				(font
					(size 1.27 1.27)
				)
			)
		)
		(duplicate_pad_numbers_are_jumpers no)
		(fp_line
			(start 0.7874 -0.4064)
			(end 0.7874 0.4064)
			(stroke
				(width 0.1524)
				(type default)
			)
			(layer "F.SilkS")
		)
		(fp_line
			(start -0.7874 -0.4064)
			(end 0.7874 -0.4064)
			(stroke
				(width 0.1524)
				(type default)
			)
			(layer "F.SilkS")
		)
		(fp_line
			(start 0.7874 0.4064)
			(end -0.7874 0.4064)
			(stroke
				(width 0.1524)
				(type default)
			)
			(layer "F.SilkS")
		)
		(fp_line
			(start -0.7874 0.4064)
			(end -0.7874 -0.4064)
			(stroke
				(width 0.1524)
				(type default)
			)
			(layer "F.SilkS")
		)
		(fp_line
			(start -0.12065 -0.305054)
			(end -0.12065 -0.2794)
			(stroke
				(width 0.1)
				(type default)
			)
			(layer "F.Fab")
		)
		(fp_line
			(start -0.67945 -0.305054)
			(end -0.12065 -0.305054)
			(stroke
				(width 0.1)
				(type default)
			)
			(layer "F.Fab")
		)
		(fp_line
			(start 0.67945 -0.3048)
			(end 0.67945 0.3048)
			(stroke
				(width 0.1)
				(type default)
			)
			(layer "F.Fab")
		)
		(fp_line
			(start 0.12065 -0.3048)
			(end 0.67945 -0.3048)
			(stroke
				(width 0.1)
				(type default)
			)
			(layer "F.Fab")
		)
		(fp_line
			(start 0.12065 -0.2794)
			(end 0.12065 -0.3048)
			(stroke
				(width 0.1)
				(type default)
			)
			(layer "F.Fab")
		)
		(fp_line
			(start -0.12065 -0.2794)
			(end 0.12065 -0.2794)
			(stroke
				(width 0.1)
				(type default)
			)
			(layer "F.Fab")
		)
		(fp_line
			(start 0.120396 0.2794)
			(end -0.12065 0.2794)
			(stroke
				(width 0.1)
				(type default)
			)
			(layer "F.Fab")
		)
		(fp_line
			(start -0.12065 0.2794)
			(end -0.12065 0.3048)
			(stroke
				(width 0.1)
				(type default)
			)
			(layer "F.Fab")
		)
		(fp_line
			(start 0.67945 0.3048)
			(end 0.120396 0.3048)
			(stroke
				(width 0.1)
				(type default)
			)
			(layer "F.Fab")
		)
		(fp_line
			(start 0.120396 0.3048)
			(end 0.120396 0.2794)
			(stroke
				(width 0.1)
				(type default)
			)
			(layer "F.Fab")
		)
		(fp_line
			(start -0.12065 0.3048)
			(end -0.67945 0.3048)
			(stroke
				(width 0.1)
				(type default)
			)
			(layer "F.Fab")
		)
		(fp_line
			(start -0.67945 0.3048)
			(end -0.67945 -0.305054)
			(stroke
				(width 0.1)
				(type default)
			)
			(layer "F.Fab")
		)
		(pad "1" smd circle
			(at -0.40005 0 90)
			(size 0 0)
			(layers "F.Cu" "F.Mask" "F.Paste")
			(net "P3V3_AUX")
		)
		(pad "2" smd circle
			(at 0.40005 0 90)
			(size 0 0)
			(layers "F.Cu" "F.Mask" "F.Paste")
			(net "RMII_RXER")
		)
	)
	(footprint ""
		(layer "F.Cu")
		(at 16.0782 -62.3062 90)
		(property "Reference" "U51"
			(at 0.9398 1.72847 90)
			(unlocked yes)
			(layer "F.SilkS")
			(effects
				(font
					(size 0.7874 0.5842)
					(thickness 0.1524)
				)
			)
		)
		(property "Value" ""
			(at 0 0 90)
			(layer "F.Fab")
			(effects
				(font
					(size 1.27 1.27)
				)
			)
		)
		(duplicate_pad_numbers_are_jumpers no)
		(fp_line
			(start 1.7272 -1.1176)
			(end 0.254 -1.1176)
			(stroke
				(width 0.1524)
				(type default)
			)
			(layer "F.SilkS")
		)
		(fp_line
			(start 1.7272 -1.1176)
			(end 1.7272 1.1176)
			(stroke
				(width 0.1524)
				(type default)
			)
			(layer "F.SilkS")
		)
		(fp_line
			(start 0.254 -1.1176)
			(end 0 -0.7366)
			(stroke
				(width 0.1524)
				(type default)
			)
			(layer "F.SilkS")
		)
		(fp_line
			(start -0.254 -1.1176)
			(end -1.7272 -1.1176)
			(stroke
				(width 0.1524)
				(type default)
			)
			(layer "F.SilkS")
		)
		(fp_line
			(start 0 -0.7366)
			(end -0.254 -1.1176)
			(stroke
				(width 0.1524)
				(type default)
			)
			(layer "F.SilkS")
		)
		(fp_line
			(start 1.7272 1.1176)
			(end -1.7272 1.1176)
			(stroke
				(width 0.1524)
				(type default)
			)
			(layer "F.SilkS")
		)
		(fp_line
			(start -1.7272 1.1176)
			(end -1.7272 -1.1176)
			(stroke
				(width 0.1524)
				(type default)
			)
			(layer "F.SilkS")
		)
		(fp_poly
			(pts
				(xy -1.905 -0.954786) (xy -2.667 -0.573786) (xy -2.667 -1.335786)
			)
			(stroke
				(width 0)
				(type default)
			)
			(fill yes)
			(layer "F.SilkS")
		)
		(fp_line
			(start 1.5748 -1.1176)
			(end -1.5748 -1.1176)
			(stroke
				(width 0.1)
				(type default)
			)
			(layer "F.Fab")
		)
		(fp_line
			(start -1.5748 -1.1176)
			(end -1.5748 1.1176)
			(stroke
				(width 0.1)
				(type default)
			)
			(layer "F.Fab")
		)
		(fp_line
			(start 1.5748 1.1176)
			(end 1.5748 -1.1176)
			(stroke
				(width 0.1)
				(type default)
			)
			(layer "F.Fab")
		)
		(fp_line
			(start -1.5748 1.1176)
			(end 1.5748 1.1176)
			(stroke
				(width 0.1)
				(type default)
			)
			(layer "F.Fab")
		)
		(fp_poly
			(pts
				(xy -1.9558 -0.649986) (xy -2.7178 -0.268986) (xy -2.7178 -1.030986)
			)
			(stroke
				(width 0)
				(type default)
			)
			(fill yes)
			(layer "F.Fab")
		)
		(pad "1" smd rect
			(at -0.999998 -0.649986)
			(size 0.3556 1.1176)
			(layers "F.Cu" "F.Mask" "F.Paste")
			(net "UART_BIC_DBG_RX_R")
		)
		(pad "2" smd rect
			(at -0.999998 0)
			(size 0.3556 1.1176)
			(layers "F.Cu" "F.Mask" "F.Paste")
			(net "GND")
		)
		(pad "3" smd rect
			(at -0.999998 0.649986)
			(size 0.3556 1.1176)
			(layers "F.Cu" "F.Mask" "F.Paste")
			(net "UART_6_BMC_TXD_R")
		)
		(pad "4" smd rect
			(at 0.999998 0.649986)
			(size 0.3556 1.1176)
			(layers "F.Cu" "F.Mask" "F.Paste")
			(net "UART_BIC_GF_TXD")
		)
		(pad "5" smd rect
			(at 0.999998 0)
			(size 0.3556 1.1176)
			(layers "F.Cu" "F.Mask" "F.Paste")
			(net "P3V3_AUX")
		)
		(pad "6" smd rect
			(at 0.999998 -0.649986)
			(size 0.3556 1.1176)
			(layers "F.Cu" "F.Mask" "F.Paste")
			(net "FM_BIC_DEBUG_SW_N")
		)
	)
	(footprint ""
		(layer "F.Cu")
		(at -6.029198 -137.995152)
		(property "Reference" "DM2"
			(at -0.3937 -0.588518 0)
			(unlocked yes)
			(layer "F.SilkS")
			(effects
				(font
					(size 0.254 0.127)
					(thickness 0.000001)
				)
				(justify left)
			)
		)
		(property "Value" ""
			(at 0 0 0)
			(layer "F.Fab")
			(effects
				(font
					(size 1.27 1.27)
				)
			)
		)
		(duplicate_pad_numbers_are_jumpers no)
		(pad "1" smd circle
			(at 0 0)
			(size 0.762 0.762)
			(layers "F.Cu" "F.Mask" "F.Paste")
			(net "Net_29")
		)
	)
)
